(kicad_pcb
	(version 20260206)
	(generator "pcbnew")
	(generator_version "10.0")
	(general
		(thickness 1.6)
		(legacy_teardrops no)
	)
	(paper "A4")
	(title_block
		(title "Bryce Canyon_R.DPB_16317-1_OCP.brd")
		(comment 1 "Bryce Canyon / footprints 526-532 of 2099")
	)
	(layers
		(0 "F.Cu" signal "TOP")
		(4 "In1.Cu" signal "L2GND")
		(6 "In2.Cu" signal "L3")
		(8 "In3.Cu" signal "L4VCC")
		(10 "In4.Cu" signal "L5VCC")
		(12 "In5.Cu" signal "L6")
		(14 "In6.Cu" signal "L7GND")
		(2 "B.Cu" signal "BOTTOM")
		(9 "F.Adhes" user "F.Adhesive")
		(11 "B.Adhes" user "B.Adhesive")
		(13 "F.Paste" user "Package Geometry/Pastemask Top")
		(15 "B.Paste" user "Package Geometry/Pastemask Bottom")
		(5 "F.SilkS" user "Ref Des/Silkscreen Top")
		(7 "B.SilkS" user "Ref Des/Silkscreen Bottom")
		(1 "F.Mask" user "Board Geometry/Soldermask Top")
		(3 "B.Mask" user "Board Geometry/Soldermask Bottom")
		(17 "Dwgs.User" user "User.Drawings")
		(19 "Cmts.User" user "User.Comments")
		(21 "Eco1.User" user "User.Eco1")
		(23 "Eco2.User" user "User.Eco2")
		(25 "Edge.Cuts" user "Board Geometry/Outline")
		(27 "Margin" user)
		(31 "F.CrtYd" user "Package Geometry/Place Bound Top")
		(29 "B.CrtYd" user "Package Geometry/Place Bound Bottom")
		(35 "F.Fab" user "Ref Des/Assembly Top")
		(33 "B.Fab" user "Ref Des/Assembly Bottom")
	)
	(footprint ""
		(layer "F.Cu")
		(at 22.987 -18.3896 -90)
		(property "Reference" "R630"
			(at 0 0 270)
			(layer "F.SilkS")
			(hide yes)
			(effects
				(font
					(size 1.27 1.27)
				)
			)
		)
		(property "Value" "1KR2F-3-GP"
			(at 0.064008 -3.993896 270)
			(unlocked yes)
			(layer "F.Fab")
			(hide yes)
			(effects
				(font
					(size 1.016 1.016)
					(thickness 0.1524)
				)
			)
		)
		(property "Device Type" "R402H16"
			(at 0.064008 -5.517896 270)
			(unlocked yes)
			(layer "F.Fab")
			(hide yes)
			(effects
				(font
					(size 1.016 1.016)
					(thickness 0.1524)
				)
			)
		)
		(duplicate_pad_numbers_are_jumpers no)
		(fp_line
			(start -0.508 -0.9398)
			(end -0.508 0.9398)
			(stroke
				(width 0.1524)
				(type default)
			)
			(layer "F.SilkS")
		)
		(fp_line
			(start 0.508 -0.9398)
			(end -0.508 -0.9398)
			(stroke
				(width 0.1524)
				(type default)
			)
			(layer "F.SilkS")
		)
		(fp_rect
			(start -0.508 0.9398)
			(end 0.508 -0.9398)
			(stroke
				(width 0)
				(type default)
			)
			(fill no)
			(layer "F.CrtYd")
		)
		(fp_rect
			(start -0.508 0.9398)
			(end 0.508 -0.9398)
			(stroke
				(width 0)
				(type default)
			)
			(fill no)
			(layer "F.Fab")
		)
		(pad "1" smd custom
			(at 0 -0.4445 270)
			(size 0.1397 0.1397)
			(layers "F.Cu" "F.Mask" "F.Paste")
			(net "P3V3_STBY_B")
			(options
				(clearance outline)
				(anchor circle)
			)
			(primitives
				(gr_poly
					(pts
						(arc
							(start -0.1778 -0.2794)
							(mid -0.249642 -0.249642)
							(end -0.2794 -0.1778)
						)
						(arc
							(start -0.2794 0.1778)
							(mid -0.249642 0.249642)
							(end -0.1778 0.2794)
						)
						(arc
							(start 0.1778 0.2794)
							(mid 0.249642 0.249642)
							(end 0.2794 0.1778)
						)
						(arc
							(start 0.2794 -0.1778)
							(mid 0.249642 -0.249642)
							(end 0.1778 -0.2794)
						)
					)
					(width 0)
					(fill yes)
				)
			)
		)
		(pad "2" smd custom
			(at 0 0.4445 270)
			(size 0.1397 0.1397)
			(layers "F.Cu" "F.Mask" "F.Paste")
			(net "SW_PWR_R_HDD24")
			(options
				(clearance outline)
				(anchor circle)
			)
			(primitives
				(gr_poly
					(pts
						(arc
							(start -0.1778 -0.2794)
							(mid -0.249642 -0.249642)
							(end -0.2794 -0.1778)
						)
						(arc
							(start -0.2794 0.1778)
							(mid -0.249642 0.249642)
							(end -0.1778 0.2794)
						)
						(arc
							(start 0.1778 0.2794)
							(mid 0.249642 0.249642)
							(end 0.2794 0.1778)
						)
						(arc
							(start 0.2794 -0.1778)
							(mid 0.249642 -0.249642)
							(end 0.1778 -0.2794)
						)
					)
					(width 0)
					(fill yes)
				)
			)
		)
	)
	(footprint ""
		(layer "F.Cu")
		(at 18.923 -35.687 90)
		(property "Reference" "R623"
			(at 0 0 90)
			(layer "F.SilkS")
			(hide yes)
			(effects
				(font
					(size 1.27 1.27)
				)
			)
		)
		(property "Value" "2R6F-GP"
			(at -0.0508 -4.8514 90)
			(unlocked yes)
			(layer "F.Fab")
			(hide yes)
			(effects
				(font
					(size 1.016 1.016)
					(thickness 0.1524)
				)
			)
		)
		(property "Device Type" "R1206H26"
			(at 0 -6.3754 90)
			(unlocked yes)
			(layer "F.Fab")
			(hide yes)
			(effects
				(font
					(size 1.016 1.016)
					(thickness 0.1524)
				)
			)
		)
		(duplicate_pad_numbers_are_jumpers no)
		(fp_line
			(start 1.016 -2.2352)
			(end 1.016 2.2352)
			(stroke
				(width 0.1524)
				(type default)
			)
			(layer "F.SilkS")
		)
		(fp_line
			(start -1.016 -2.2352)
			(end 1.016 -2.2352)
			(stroke
				(width 0.1524)
				(type default)
			)
			(layer "F.SilkS")
		)
		(fp_line
			(start 1.016 2.2352)
			(end -1.016 2.2352)
			(stroke
				(width 0.1524)
				(type default)
			)
			(layer "F.SilkS")
		)
		(fp_line
			(start -1.016 2.2352)
			(end -1.016 -2.2352)
			(stroke
				(width 0.1524)
				(type default)
			)
			(layer "F.SilkS")
		)
		(fp_rect
			(start -1.0922 2.3114)
			(end 1.0922 -2.3114)
			(stroke
				(width 0)
				(type default)
			)
			(fill no)
			(layer "F.CrtYd")
		)
		(fp_poly
			(pts
				(xy -1.0922 -2.3114) (xy 1.0922 -2.3114) (xy 1.0922 2.3114) (xy -1.0922 2.3114)
			)
			(stroke
				(width 0)
				(type default)
			)
			(fill no)
			(layer "F.Fab")
		)
		(pad "1" smd rect
			(at 0 -1.397 90)
			(size 1.651 1.27)
			(layers "F.Cu" "F.Mask" "F.Paste")
			(net "P12V_HDD24")
		)
		(pad "2" smd rect
			(at 0 1.397 90)
			(size 1.651 1.27)
			(layers "F.Cu" "F.Mask" "F.Paste")
			(net "12V_PRE_24")
		)
	)
	(footprint ""
		(layer "F.Cu")
		(at 215.51646 -168.70426 90)
		(property "Reference" "U7"
			(at 0 0 90)
			(layer "F.SilkS")
			(hide yes)
			(effects
				(font
					(size 1.27 1.27)
				)
			)
		)
		(property "Value" "TCA9555PWR-GP"
			(at 0 -6.9342 90)
			(unlocked yes)
			(layer "F.Fab")
			(hide yes)
			(effects
				(font
					(size 1.016 1.016)
					(thickness 0.1524)
				)
			)
		)
		(property "Device Type" "TSOIC24H48"
			(at 0 -8.5852 90)
			(unlocked yes)
			(layer "F.Fab")
			(hide yes)
			(effects
				(font
					(size 1.016 1.016)
					(thickness 0.1524)
				)
			)
		)
		(duplicate_pad_numbers_are_jumpers no)
		(fp_line
			(start 3.81 -1.397)
			(end 3.81 1.397)
			(stroke
				(width 0.1524)
				(type default)
			)
			(layer "F.SilkS")
		)
		(fp_line
			(start -4.2291 -1.397)
			(end 3.81 -1.397)
			(stroke
				(width 0.1524)
				(type default)
			)
			(layer "F.SilkS")
		)
		(fp_line
			(start -4.2291 -0.8001)
			(end -3.429 0)
			(stroke
				(width 0.1524)
				(type default)
			)
			(layer "F.SilkS")
		)
		(fp_line
			(start -3.429 0)
			(end -4.2291 0.8001)
			(stroke
				(width 0.1524)
				(type default)
			)
			(layer "F.SilkS")
		)
		(fp_line
			(start 3.81 1.397)
			(end -4.2291 1.397)
			(stroke
				(width 0.1524)
				(type default)
			)
			(layer "F.SilkS")
		)
		(fp_line
			(start -4.22656 3.81)
			(end -4.2291 1.397)
			(stroke
				(width 0.508)
				(type default)
			)
			(layer "F.SilkS")
		)
		(fp_line
			(start -4.2291 3.937)
			(end -4.2291 -1.397)
			(stroke
				(width 0.1524)
				(type default)
			)
			(layer "F.SilkS")
		)
		(fp_poly
			(pts
				(xy -3.90652 -1.8542) (xy 3.90652 -1.8542) (xy 3.90652 1.8542) (xy -3.90652 1.8542)
			)
			(stroke
				(width 0)
				(type default)
			)
			(fill yes)
			(layer "F.SilkS")
		)
		(fp_poly
			(pts
				(xy -4.2164 3.81) (xy 4.2164 3.81) (xy 4.22656 -3.81) (xy -4.2164 -3.81)
			)
			(stroke
				(width 0)
				(type default)
			)
			(fill no)
			(layer "F.CrtYd")
		)
		(fp_poly
			(pts
				(xy -4.22656 -3.81) (xy 4.22656 -3.81) (xy 4.22656 3.81) (xy -4.22656 3.81)
			)
			(stroke
				(width 0)
				(type default)
			)
			(fill no)
			(layer "F.Fab")
		)
		(pad "1" smd rect
			(at -3.57632 2.8194 90)
			(size 0.3556 1.524)
			(layers "F.Cu" "F.Mask" "F.Paste")
			(net "IO_EXP6_INT_N")
		)
		(pad "2" smd rect
			(at -2.92608 2.8194 90)
			(size 0.3556 1.524)
			(layers "F.Cu" "F.Mask" "F.Paste")
			(net "IO_EXP6_A1")
		)
		(pad "3" smd rect
			(at -2.27584 2.8194 90)
			(size 0.3556 1.524)
			(layers "F.Cu" "F.Mask" "F.Paste")
			(net "IO_EXP6_A2")
		)
		(pad "4" smd rect
			(at -1.6256 2.8194 90)
			(size 0.3556 1.524)
			(layers "F.Cu" "F.Mask" "F.Paste")
			(net "DRIVE_B_32_INS")
		)
		(pad "5" smd rect
			(at -0.97536 2.8194 90)
			(size 0.3556 1.524)
			(layers "F.Cu" "F.Mask" "F.Paste")
			(net "DRIVE_B_33_INS")
		)
		(pad "6" smd rect
			(at -0.32512 2.8194 90)
			(size 0.3556 1.524)
			(layers "F.Cu" "F.Mask" "F.Paste")
			(net "DRIVE_B_34_INS")
		)
		(pad "7" smd rect
			(at 0.32512 2.8194 90)
			(size 0.3556 1.524)
			(layers "F.Cu" "F.Mask" "F.Paste")
			(net "DRIVE_B_35_INS")
		)
		(pad "8" smd rect
			(at 0.97536 2.8194 90)
			(size 0.3556 1.524)
			(layers "F.Cu" "F.Mask" "F.Paste")
			(net "Net_265")
		)
		(pad "9" smd rect
			(at 1.6256 2.8194 90)
			(size 0.3556 1.524)
			(layers "F.Cu" "F.Mask" "F.Paste")
			(net "Net_264")
		)
		(pad "10" smd rect
			(at 2.27584 2.8194 90)
			(size 0.3556 1.524)
			(layers "F.Cu" "F.Mask" "F.Paste")
			(net "Net_263")
		)
		(pad "11" smd rect
			(at 2.92608 2.8194 90)
			(size 0.3556 1.524)
			(layers "F.Cu" "F.Mask" "F.Paste")
			(net "Net_262")
		)
		(pad "12" smd rect
			(at 3.57632 2.8194 90)
			(size 0.3556 1.524)
			(layers "F.Cu" "F.Mask" "F.Paste")
			(net "GND")
		)
		(pad "13" smd rect
			(at 3.57632 -2.8194 90)
			(size 0.3556 1.524)
			(layers "F.Cu" "F.Mask" "F.Paste")
			(net "DRAWER_CLOSED_N")
		)
		(pad "14" smd rect
			(at 2.92608 -2.8194 90)
			(size 0.3556 1.524)
			(layers "F.Cu" "F.Mask" "F.Paste")
			(net "FAN_0_INS_N")
		)
		(pad "15" smd rect
			(at 2.27584 -2.8194 90)
			(size 0.3556 1.524)
			(layers "F.Cu" "F.Mask" "F.Paste")
			(net "FAN_1_INS_N")
		)
		(pad "16" smd rect
			(at 1.6256 -2.8194 90)
			(size 0.3556 1.524)
			(layers "F.Cu" "F.Mask" "F.Paste")
			(net "FAN_2_INS_N")
		)
		(pad "17" smd rect
			(at 0.97536 -2.8194 90)
			(size 0.3556 1.524)
			(layers "F.Cu" "F.Mask" "F.Paste")
			(net "FAN_3_INS_N")
		)
		(pad "18" smd rect
			(at 0.32512 -2.8194 90)
			(size 0.3556 1.524)
			(layers "F.Cu" "F.Mask" "F.Paste")
			(net "IOM_A_INS_N")
		)
		(pad "19" smd rect
			(at -0.32512 -2.8194 90)
			(size 0.3556 1.524)
			(layers "F.Cu" "F.Mask" "F.Paste")
			(net "IOM_B_INS_N")
		)
		(pad "20" smd rect
			(at -0.97536 -2.8194 90)
			(size 0.3556 1.524)
			(layers "F.Cu" "F.Mask" "F.Paste")
			(net "SCC_A_INS_N")
		)
		(pad "21" smd rect
			(at -1.6256 -2.8194 90)
			(size 0.3556 1.524)
			(layers "F.Cu" "F.Mask" "F.Paste")
			(net "IO_EXP6_A0")
		)
		(pad "22" smd rect
			(at -2.27584 -2.8194 90)
			(size 0.3556 1.524)
			(layers "F.Cu" "F.Mask" "F.Paste")
			(net "IO_EXP6_SCL")
		)
		(pad "23" smd rect
			(at -2.92608 -2.8194 90)
			(size 0.3556 1.524)
			(layers "F.Cu" "F.Mask" "F.Paste")
			(net "IO_EXP6_SDA")
		)
		(pad "24" smd rect
			(at -3.57632 -2.8194 90)
			(size 0.3556 1.524)
			(layers "F.Cu" "F.Mask" "F.Paste")
			(net "P3V3_STBY_B")
		)
	)
	(footprint ""
		(layer "F.Cu")
		(at 46.228 -150.622 -90)
		(property "Reference" "C203"
			(at 0 0 270)
			(layer "F.SilkS")
			(hide yes)
			(effects
				(font
					(size 1.27 1.27)
				)
			)
		)
		(property "Value" "SC4D7U25V5KX-1-GP"
			(at -0.0762 -6.1214 270)
			(unlocked yes)
			(layer "F.Fab")
			(hide yes)
			(effects
				(font
					(size 1.016 1.016)
					(thickness 0.1524)
				)
			)
		)
		(property "Device Type" "C805H58"
			(at -0.0762 -8.1534 270)
			(unlocked yes)
			(layer "F.Fab")
			(hide yes)
			(effects
				(font
					(size 1.016 1.016)
					(thickness 0.1524)
				)
			)
		)
		(duplicate_pad_numbers_are_jumpers no)
		(fp_line
			(start 0.635 0)
			(end -0.635 0)
			(stroke
				(width 0.508)
				(type default)
			)
			(layer "F.SilkS")
		)
		(fp_rect
			(start -0.9652 1.778)
			(end 0.9652 -1.778)
			(stroke
				(width 0)
				(type default)
			)
			(fill no)
			(layer "F.CrtYd")
		)
		(fp_poly
			(pts
				(xy -0.9652 -1.778) (xy 0.9652 -1.778) (xy 0.9652 1.778) (xy -0.9652 1.778)
			)
			(stroke
				(width 0)
				(type default)
			)
			(fill no)
			(layer "F.Fab")
		)
		(pad "1" smd rect
			(at 0 -0.9652 270)
			(size 1.397 1.143)
			(layers "F.Cu" "F.Mask" "F.Paste")
			(net "P12V_HDD13")
		)
		(pad "2" smd rect
			(at 0 0.9652 270)
			(size 1.397 1.143)
			(layers "F.Cu" "F.Mask" "F.Paste")
			(net "GND")
		)
	)
	(footprint ""
		(layer "F.Cu")
		(at 323.3166 -132.437124)
		(property "Reference" "VIA38"
			(at 0 0 0)
			(layer "F.SilkS")
			(hide yes)
			(effects
				(font
					(size 1.27 1.27)
				)
			)
		)
		(property "Value" "100OHM-8L-2D36MM-L16-GP"
			(at -3.4036 -0.4572 0)
			(unlocked yes)
			(layer "F.Fab")
			(hide yes)
			(effects
				(font
					(size 1.016 1.016)
					(thickness 0.1524)
				)
			)
		)
		(property "Device Type" "VIA-PCIE-4P-427097"
			(at -3.4036 -1.9812 0)
			(unlocked yes)
			(layer "F.Fab")
			(hide yes)
			(effects
				(font
					(size 1.016 1.016)
					(thickness 0.1524)
				)
			)
		)
		(duplicate_pad_numbers_are_jumpers no)
		(fp_rect
			(start -2.1336 0.4826)
			(end 2.1336 -0.4826)
			(stroke
				(width 0)
				(type default)
			)
			(fill no)
			(layer "F.CrtYd")
		)
		(fp_rect
			(start -2.1336 0.4826)
			(end 2.1336 -0.4826)
			(stroke
				(width 0)
				(type default)
			)
			(fill no)
			(layer "F.Fab")
		)
		(pad "1" thru_hole circle
			(at -1.651 0)
			(size 0.508 0.508)
			(drill 0.254)
			(layers "*.Cu" "*.Mask")
			(remove_unused_layers no)
			(net "GND")
			(clearance 0.2286)
			(thermal_gap 0.2286)
		)
		(pad "2" thru_hole circle
			(at -0.635 0)
			(size 0.508 0.508)
			(drill 0.254)
			(layers "*.Cu" "*.Mask")
			(remove_unused_layers no)
			(net "PHY_DRV_B_TO_SCC_B_18_DP")
			(clearance 0.2286)
			(thermal_gap 0.2286)
		)
		(pad "3" thru_hole circle
			(at 0.635 0)
			(size 0.508 0.508)
			(drill 0.254)
			(layers "*.Cu" "*.Mask")
			(remove_unused_layers no)
			(net "PHY_DRV_B_TO_SCC_B_18_DN")
			(clearance 0.2286)
			(thermal_gap 0.2286)
		)
		(pad "4" thru_hole circle
			(at 1.651 0)
			(size 0.508 0.508)
			(drill 0.254)
			(layers "*.Cu" "*.Mask")
			(remove_unused_layers no)
			(net "GND")
			(clearance 0.2286)
			(thermal_gap 0.2286)
		)
	)
	(footprint ""
		(layer "F.Cu")
		(at 463.423 -133.858 90)
		(property "Reference" "D22"
			(at 0 0 90)
			(layer "F.SilkS")
			(hide yes)
			(effects
				(font
					(size 1.27 1.27)
				)
			)
		)
		(property "Value" "RB551V30-GP"
			(at 0 -6.7818 90)
			(unlocked yes)
			(layer "F.Fab")
			(hide yes)
			(effects
				(font
					(size 1.016 1.016)
					(thickness 0.1524)
				)
			)
		)
		(property "Device Type" "SOD323AKH38"
			(at 0 -8.6868 90)
			(unlocked yes)
			(layer "F.Fab")
			(hide yes)
			(effects
				(font
					(size 1.016 1.016)
					(thickness 0.1524)
				)
			)
		)
		(duplicate_pad_numbers_are_jumpers no)
		(fp_line
			(start 0.889 -1.9304)
			(end 0.889 2.159)
			(stroke
				(width 0.1524)
				(type default)
			)
			(layer "F.SilkS")
		)
		(fp_line
			(start -0.889 -1.9304)
			(end 0.889 -1.9304)
			(stroke
				(width 0.1524)
				(type default)
			)
			(layer "F.SilkS")
		)
		(fp_line
			(start 0.762 2.0574)
			(end -0.762 2.0574)
			(stroke
				(width 0.508)
				(type default)
			)
			(layer "F.SilkS")
		)
		(fp_line
			(start 0.889 2.159)
			(end -0.889 2.159)
			(stroke
				(width 0.1524)
				(type default)
			)
			(layer "F.SilkS")
		)
		(fp_line
			(start -0.889 2.159)
			(end -0.889 -1.9304)
			(stroke
				(width 0.1524)
				(type default)
			)
			(layer "F.SilkS")
		)
		(fp_rect
			(start -1.016 2.3114)
			(end 1.016 -2.0066)
			(stroke
				(width 0)
				(type default)
			)
			(fill no)
			(layer "F.CrtYd")
		)
		(fp_poly
			(pts
				(xy -1.016 -2.0066) (xy 1.016 -2.0066) (xy 1.016 2.3114) (xy -1.016 2.3114)
			)
			(stroke
				(width 0)
				(type default)
			)
			(fill no)
			(layer "F.Fab")
		)
		(pad "A" smd rect
			(at 0 -1.143 90)
			(size 0.5588 1.016)
			(layers "F.Cu" "F.Mask" "F.Paste")
			(net "SW_HDD_R22")
		)
		(pad "K" smd rect
			(at 0 1.143 90)
			(size 0.5588 1.016)
			(layers "F.Cu" "F.Mask" "F.Paste")
			(net "SW_HDD_N22")
		)
	)
	(footprint ""
		(layer "F.Cu")
		(at 170.18 -363.22 -90)
		(property "Reference" "R1003"
			(at 0 0 270)
			(layer "F.SilkS")
			(hide yes)
			(effects
				(font
					(size 1.27 1.27)
				)
			)
		)
		(property "Value" "100KR2F-L1-GP"
			(at 0.064008 -3.993896 270)
			(unlocked yes)
			(layer "F.Fab")
			(hide yes)
			(effects
				(font
					(size 1.016 1.016)
					(thickness 0.1524)
				)
			)
		)
		(property "Device Type" "R402H16"
			(at 0.064008 -5.517896 270)
			(unlocked yes)
			(layer "F.Fab")
			(hide yes)
			(effects
				(font
					(size 1.016 1.016)
					(thickness 0.1524)
				)
			)
		)
		(duplicate_pad_numbers_are_jumpers no)
		(fp_line
			(start -0.508 -0.9398)
			(end -0.508 0.9398)
			(stroke
				(width 0.1524)
				(type default)
			)
			(layer "F.SilkS")
		)
		(fp_line
			(start 0.508 -0.9398)
			(end -0.508 -0.9398)
			(stroke
				(width 0.1524)
				(type default)
			)
			(layer "F.SilkS")
		)
		(fp_rect
			(start -0.508 0.9398)
			(end 0.508 -0.9398)
			(stroke
				(width 0)
				(type default)
			)
			(fill no)
			(layer "F.CrtYd")
		)
		(fp_rect
			(start -0.508 0.9398)
			(end 0.508 -0.9398)
			(stroke
				(width 0)
				(type default)
			)
			(fill no)
			(layer "F.Fab")
		)
		(pad "1" smd custom
			(at 0 -0.4445 270)
			(size 0.1397 0.1397)
			(layers "F.Cu" "F.Mask" "F.Paste")
			(net "MB0_VCAP_R")
			(options
				(clearance outline)
				(anchor circle)
			)
			(primitives
				(gr_poly
					(pts
						(arc
							(start -0.1778 -0.2794)
							(mid -0.249642 -0.249642)
							(end -0.2794 -0.1778)
						)
						(arc
							(start -0.2794 0.1778)
							(mid -0.249642 0.249642)
							(end -0.1778 0.2794)
						)
						(arc
							(start 0.1778 0.2794)
							(mid 0.249642 0.249642)
							(end 0.2794 0.1778)
						)
						(arc
							(start 0.2794 -0.1778)
							(mid 0.249642 -0.249642)
							(end 0.1778 -0.2794)
						)
					)
					(width 0)
					(fill yes)
				)
			)
		)
		(pad "2" smd custom
			(at 0 0.4445 270)
			(size 0.1397 0.1397)
			(layers "F.Cu" "F.Mask" "F.Paste")
			(net "MB0_PSET_R")
			(options
				(clearance outline)
				(anchor circle)
			)
			(primitives
				(gr_poly
					(pts
						(arc
							(start -0.1778 -0.2794)
							(mid -0.249642 -0.249642)
							(end -0.2794 -0.1778)
						)
						(arc
							(start -0.2794 0.1778)
							(mid -0.249642 0.249642)
							(end -0.1778 0.2794)
						)
						(arc
							(start 0.1778 0.2794)
							(mid 0.249642 0.249642)
							(end 0.2794 0.1778)
						)
						(arc
							(start 0.2794 -0.1778)
							(mid 0.249642 -0.249642)
							(end 0.1778 -0.2794)
						)
					)
					(width 0)
					(fill yes)
				)
			)
		)
	)
)
